(kicad_pcb
	(version 20260206)
	(generator "pcbnew")
	(generator_version "10.0")
	(general
		(thickness 1.6)
		(legacy_teardrops no)
	)
	(paper "A4")
	(title_block
		(title "15969-1a.1015WZS0858.brd")
		(comment 1 "Tioga Pass / footprints 52-58 of 295")
	)
	(layers
		(0 "F.Cu" signal "TOP")
		(4 "In1.Cu" signal "L2GND")
		(6 "In2.Cu" signal "L3")
		(8 "In3.Cu" signal "L4")
		(10 "In4.Cu" signal "L5GND")
		(2 "B.Cu" signal "BOTTOM")
		(9 "F.Adhes" user "F.Adhesive")
		(11 "B.Adhes" user "B.Adhesive")
		(13 "F.Paste" user "Package Geometry/Pastemask Top")
		(15 "B.Paste" user "Package Geometry/Pastemask Bottom")
		(5 "F.SilkS" user "Ref Des/Silkscreen Top")
		(7 "B.SilkS" user "Ref Des/Silkscreen Bottom")
		(1 "F.Mask" user "Board Geometry/Soldermask Top")
		(3 "B.Mask" user "Board Geometry/Soldermask Bottom")
		(17 "Dwgs.User" user "User.Drawings")
		(19 "Cmts.User" user "User.Comments")
		(21 "Eco1.User" user "User.Eco1")
		(23 "Eco2.User" user "User.Eco2")
		(25 "Edge.Cuts" user "Board Geometry/Outline")
		(27 "Margin" user)
		(31 "F.CrtYd" user "Package Geometry/Place Bound Top")
		(29 "B.CrtYd" user "Package Geometry/Place Bound Bottom")
		(35 "F.Fab" user "Ref Des/Assembly Top")
		(33 "B.Fab" user "Ref Des/Assembly Bottom")
	)
	(footprint ""
		(layer "F.Cu")
		(at 65.6082 -24.0792 180)
		(property "Reference" "R44"
			(at 0 0 180)
			(layer "F.SilkS")
			(hide yes)
			(effects
				(font
					(size 1.27 1.27)
				)
			)
		)
		(property "Value" "4K7R2F-GP"
			(at 0.064008 -3.993896 180)
			(unlocked yes)
			(layer "F.Fab")
			(hide yes)
			(effects
				(font
					(size 1.016 1.016)
					(thickness 0.1524)
				)
			)
		)
		(property "Device Type" "R402H16"
			(at 0.064008 -5.517896 180)
			(unlocked yes)
			(layer "F.Fab")
			(hide yes)
			(effects
				(font
					(size 1.016 1.016)
					(thickness 0.1524)
				)
			)
		)
		(duplicate_pad_numbers_are_jumpers no)
		(fp_line
			(start 0.508 -0.9398)
			(end -0.508 -0.9398)
			(stroke
				(width 0.1524)
				(type default)
			)
			(layer "F.SilkS")
		)
		(fp_line
			(start -0.508 -0.9398)
			(end -0.508 0.9398)
			(stroke
				(width 0.1524)
				(type default)
			)
			(layer "F.SilkS")
		)
		(fp_rect
			(start -0.508 0.9398)
			(end 0.508 -0.9398)
			(stroke
				(width 0)
				(type default)
			)
			(fill no)
			(layer "F.CrtYd")
		)
		(fp_rect
			(start -0.508 0.9398)
			(end 0.508 -0.9398)
			(stroke
				(width 0)
				(type default)
			)
			(fill no)
			(layer "F.Fab")
		)
		(pad "1" smd custom
			(at 0 -0.4445 180)
			(size 0.1397 0.1397)
			(layers "F.Cu" "F.Mask" "F.Paste")
			(net "P3V3_STBY")
			(options
				(clearance outline)
				(anchor circle)
			)
			(primitives
				(gr_poly
					(pts
						(arc
							(start -0.1778 -0.2794)
							(mid -0.249642 -0.249642)
							(end -0.2794 -0.1778)
						)
						(arc
							(start -0.2794 0.1778)
							(mid -0.249642 0.249642)
							(end -0.1778 0.2794)
						)
						(arc
							(start 0.1778 0.2794)
							(mid 0.249642 0.249642)
							(end 0.2794 0.1778)
						)
						(arc
							(start 0.2794 -0.1778)
							(mid 0.249642 -0.249642)
							(end 0.1778 -0.2794)
						)
					)
					(width 0)
					(fill yes)
				)
			)
		)
		(pad "2" smd custom
			(at 0 0.4445 180)
			(size 0.1397 0.1397)
			(layers "F.Cu" "F.Mask" "F.Paste")
			(net "PCIE_SLOT3_PRSNT2_2_N")
			(options
				(clearance outline)
				(anchor circle)
			)
			(primitives
				(gr_poly
					(pts
						(arc
							(start -0.1778 -0.2794)
							(mid -0.249642 -0.249642)
							(end -0.2794 -0.1778)
						)
						(arc
							(start -0.2794 0.1778)
							(mid -0.249642 0.249642)
							(end -0.1778 0.2794)
						)
						(arc
							(start 0.1778 0.2794)
							(mid 0.249642 0.249642)
							(end 0.2794 0.1778)
						)
						(arc
							(start 0.2794 -0.1778)
							(mid 0.249642 -0.249642)
							(end 0.1778 -0.2794)
						)
					)
					(width 0)
					(fill yes)
				)
			)
		)
	)
	(footprint ""
		(layer "F.Cu")
		(at 128.6256 1.9558 90)
		(property "Reference" "R26"
			(at 0 0 90)
			(layer "F.SilkS")
			(hide yes)
			(effects
				(font
					(size 1.27 1.27)
				)
			)
		)
		(property "Value" "4K7R2F-GP"
			(at 0.064008 -3.993896 90)
			(unlocked yes)
			(layer "F.Fab")
			(hide yes)
			(effects
				(font
					(size 1.016 1.016)
					(thickness 0.1524)
				)
			)
		)
		(property "Device Type" "R402H16"
			(at 0.064008 -5.517896 90)
			(unlocked yes)
			(layer "F.Fab")
			(hide yes)
			(effects
				(font
					(size 1.016 1.016)
					(thickness 0.1524)
				)
			)
		)
		(duplicate_pad_numbers_are_jumpers no)
		(fp_line
			(start 0.508 -0.9398)
			(end -0.508 -0.9398)
			(stroke
				(width 0.1524)
				(type default)
			)
			(layer "F.SilkS")
		)
		(fp_line
			(start -0.508 -0.9398)
			(end -0.508 0.9398)
			(stroke
				(width 0.1524)
				(type default)
			)
			(layer "F.SilkS")
		)
		(fp_rect
			(start -0.508 0.9398)
			(end 0.508 -0.9398)
			(stroke
				(width 0)
				(type default)
			)
			(fill no)
			(layer "F.CrtYd")
		)
		(fp_rect
			(start -0.508 0.9398)
			(end 0.508 -0.9398)
			(stroke
				(width 0)
				(type default)
			)
			(fill no)
			(layer "F.Fab")
		)
		(pad "1" smd custom
			(at 0 -0.4445 90)
			(size 0.1397 0.1397)
			(layers "F.Cu" "F.Mask" "F.Paste")
			(net "P3V3_STBY")
			(options
				(clearance outline)
				(anchor circle)
			)
			(primitives
				(gr_poly
					(pts
						(arc
							(start -0.1778 -0.2794)
							(mid -0.249642 -0.249642)
							(end -0.2794 -0.1778)
						)
						(arc
							(start -0.2794 0.1778)
							(mid -0.249642 0.249642)
							(end -0.1778 0.2794)
						)
						(arc
							(start 0.1778 0.2794)
							(mid 0.249642 0.249642)
							(end 0.2794 0.1778)
						)
						(arc
							(start 0.2794 -0.1778)
							(mid 0.249642 -0.249642)
							(end 0.1778 -0.2794)
						)
					)
					(width 0)
					(fill yes)
				)
			)
		)
		(pad "2" smd custom
			(at 0 0.4445 90)
			(size 0.1397 0.1397)
			(layers "F.Cu" "F.Mask" "F.Paste")
			(net "SMCLK_PCH_DEVICE")
			(options
				(clearance outline)
				(anchor circle)
			)
			(primitives
				(gr_poly
					(pts
						(arc
							(start -0.1778 -0.2794)
							(mid -0.249642 -0.249642)
							(end -0.2794 -0.1778)
						)
						(arc
							(start -0.2794 0.1778)
							(mid -0.249642 0.249642)
							(end -0.1778 0.2794)
						)
						(arc
							(start 0.1778 0.2794)
							(mid 0.249642 0.249642)
							(end 0.2794 0.1778)
						)
						(arc
							(start 0.2794 -0.1778)
							(mid 0.249642 -0.249642)
							(end 0.1778 -0.2794)
						)
					)
					(width 0)
					(fill yes)
				)
			)
		)
	)
	(footprint ""
		(layer "F.Cu")
		(at 126.746 2.5908 180)
		(property "Reference" "R155"
			(at 0 0 180)
			(layer "F.SilkS")
			(hide yes)
			(effects
				(font
					(size 1.27 1.27)
				)
			)
		)
		(property "Value" "10KR2F-2-GP"
			(at 0.064008 -3.993896 180)
			(unlocked yes)
			(layer "F.Fab")
			(hide yes)
			(effects
				(font
					(size 1.016 1.016)
					(thickness 0.1524)
				)
			)
		)
		(property "Device Type" "R402H16"
			(at 0.064008 -5.517896 180)
			(unlocked yes)
			(layer "F.Fab")
			(hide yes)
			(effects
				(font
					(size 1.016 1.016)
					(thickness 0.1524)
				)
			)
		)
		(duplicate_pad_numbers_are_jumpers no)
		(fp_line
			(start 0.508 -0.9398)
			(end -0.508 -0.9398)
			(stroke
				(width 0.1524)
				(type default)
			)
			(layer "F.SilkS")
		)
		(fp_line
			(start -0.508 -0.9398)
			(end -0.508 0.9398)
			(stroke
				(width 0.1524)
				(type default)
			)
			(layer "F.SilkS")
		)
		(fp_rect
			(start -0.508 0.9398)
			(end 0.508 -0.9398)
			(stroke
				(width 0)
				(type default)
			)
			(fill no)
			(layer "F.CrtYd")
		)
		(fp_rect
			(start -0.508 0.9398)
			(end 0.508 -0.9398)
			(stroke
				(width 0)
				(type default)
			)
			(fill no)
			(layer "F.Fab")
		)
		(pad "1" smd custom
			(at 0 -0.4445 180)
			(size 0.1397 0.1397)
			(layers "F.Cu" "F.Mask" "F.Paste")
			(net "P3V3_STBY")
			(options
				(clearance outline)
				(anchor circle)
			)
			(primitives
				(gr_poly
					(pts
						(arc
							(start -0.1778 -0.2794)
							(mid -0.249642 -0.249642)
							(end -0.2794 -0.1778)
						)
						(arc
							(start -0.2794 0.1778)
							(mid -0.249642 0.249642)
							(end -0.1778 0.2794)
						)
						(arc
							(start 0.1778 0.2794)
							(mid 0.249642 0.249642)
							(end 0.2794 0.1778)
						)
						(arc
							(start 0.2794 -0.1778)
							(mid 0.249642 -0.249642)
							(end 0.1778 -0.2794)
						)
					)
					(width 0)
					(fill yes)
				)
			)
		)
		(pad "2" smd custom
			(at 0 0.4445 180)
			(size 0.1397 0.1397)
			(layers "F.Cu" "F.Mask" "F.Paste")
			(net "GPIO_P_IO1_7")
			(options
				(clearance outline)
				(anchor circle)
			)
			(primitives
				(gr_poly
					(pts
						(arc
							(start -0.1778 -0.2794)
							(mid -0.249642 -0.249642)
							(end -0.2794 -0.1778)
						)
						(arc
							(start -0.2794 0.1778)
							(mid -0.249642 0.249642)
							(end -0.1778 0.2794)
						)
						(arc
							(start 0.1778 0.2794)
							(mid 0.249642 0.249642)
							(end 0.2794 0.1778)
						)
						(arc
							(start 0.2794 -0.1778)
							(mid 0.249642 -0.249642)
							(end 0.1778 -0.2794)
						)
					)
					(width 0)
					(fill yes)
				)
			)
		)
	)
	(footprint ""
		(layer "F.Cu")
		(at 17.1958 -22.9616 90)
		(property "Reference" "R86"
			(at 0 0 90)
			(layer "F.SilkS")
			(hide yes)
			(effects
				(font
					(size 1.27 1.27)
				)
			)
		)
		(property "Value" "10R2F-L-GP"
			(at 0.064008 -3.993896 90)
			(unlocked yes)
			(layer "F.Fab")
			(hide yes)
			(effects
				(font
					(size 1.016 1.016)
					(thickness 0.1524)
				)
			)
		)
		(property "Device Type" "R402H14"
			(at 0.064008 -5.517896 90)
			(unlocked yes)
			(layer "F.Fab")
			(hide yes)
			(effects
				(font
					(size 1.016 1.016)
					(thickness 0.1524)
				)
			)
		)
		(duplicate_pad_numbers_are_jumpers no)
		(fp_line
			(start 0.508 -0.9398)
			(end -0.508 -0.9398)
			(stroke
				(width 0.1524)
				(type default)
			)
			(layer "F.SilkS")
		)
		(fp_line
			(start -0.508 -0.9398)
			(end -0.508 0.9398)
			(stroke
				(width 0.1524)
				(type default)
			)
			(layer "F.SilkS")
		)
		(fp_rect
			(start -0.508 0.9398)
			(end 0.508 -0.9398)
			(stroke
				(width 0)
				(type default)
			)
			(fill no)
			(layer "F.CrtYd")
		)
		(fp_rect
			(start -0.508 0.9398)
			(end 0.508 -0.9398)
			(stroke
				(width 0)
				(type default)
			)
			(fill no)
			(layer "F.Fab")
		)
		(pad "1" smd custom
			(at 0 -0.4445 90)
			(size 0.1397 0.1397)
			(layers "F.Cu" "F.Mask" "F.Paste")
			(net "P12V")
			(options
				(clearance outline)
				(anchor circle)
			)
			(primitives
				(gr_poly
					(pts
						(arc
							(start -0.1778 -0.2794)
							(mid -0.249642 -0.249642)
							(end -0.2794 -0.1778)
						)
						(arc
							(start -0.2794 0.1778)
							(mid -0.249642 0.249642)
							(end -0.1778 0.2794)
						)
						(arc
							(start 0.1778 0.2794)
							(mid 0.249642 0.249642)
							(end 0.2794 0.1778)
						)
						(arc
							(start 0.2794 -0.1778)
							(mid 0.249642 -0.249642)
							(end 0.1778 -0.2794)
						)
					)
					(width 0)
					(fill yes)
				)
			)
		)
		(pad "2" smd custom
			(at 0 0.4445 90)
			(size 0.1397 0.1397)
			(layers "F.Cu" "F.Mask" "F.Paste")
			(net "SLOT3_P12V_SENSE_VP_R")
			(options
				(clearance outline)
				(anchor circle)
			)
			(primitives
				(gr_poly
					(pts
						(arc
							(start -0.1778 -0.2794)
							(mid -0.249642 -0.249642)
							(end -0.2794 -0.1778)
						)
						(arc
							(start -0.2794 0.1778)
							(mid -0.249642 0.249642)
							(end -0.1778 0.2794)
						)
						(arc
							(start 0.1778 0.2794)
							(mid 0.249642 0.249642)
							(end 0.2794 0.1778)
						)
						(arc
							(start 0.2794 -0.1778)
							(mid 0.249642 -0.249642)
							(end 0.1778 -0.2794)
						)
					)
					(width 0)
					(fill yes)
				)
			)
		)
	)
	(footprint ""
		(layer "F.Cu")
		(at 19.4056 -15.758922 180)
		(property "Reference" "R82"
			(at 0 0 180)
			(layer "F.SilkS")
			(hide yes)
			(effects
				(font
					(size 1.27 1.27)
				)
			)
		)
		(property "Value" "10KR2F-2-GP"
			(at 0.064008 -3.993896 180)
			(unlocked yes)
			(layer "F.Fab")
			(hide yes)
			(effects
				(font
					(size 1.016 1.016)
					(thickness 0.1524)
				)
			)
		)
		(property "Device Type" "R402H16"
			(at 0.064008 -5.517896 180)
			(unlocked yes)
			(layer "F.Fab")
			(hide yes)
			(effects
				(font
					(size 1.016 1.016)
					(thickness 0.1524)
				)
			)
		)
		(duplicate_pad_numbers_are_jumpers no)
		(fp_line
			(start 0.508 -0.9398)
			(end -0.508 -0.9398)
			(stroke
				(width 0.1524)
				(type default)
			)
			(layer "F.SilkS")
		)
		(fp_line
			(start -0.508 -0.9398)
			(end -0.508 0.9398)
			(stroke
				(width 0.1524)
				(type default)
			)
			(layer "F.SilkS")
		)
		(fp_rect
			(start -0.508 0.9398)
			(end 0.508 -0.9398)
			(stroke
				(width 0)
				(type default)
			)
			(fill no)
			(layer "F.CrtYd")
		)
		(fp_rect
			(start -0.508 0.9398)
			(end 0.508 -0.9398)
			(stroke
				(width 0)
				(type default)
			)
			(fill no)
			(layer "F.Fab")
		)
		(pad "1" smd custom
			(at 0 -0.4445 180)
			(size 0.1397 0.1397)
			(layers "F.Cu" "F.Mask" "F.Paste")
			(net "P3V3_STBY")
			(options
				(clearance outline)
				(anchor circle)
			)
			(primitives
				(gr_poly
					(pts
						(arc
							(start -0.1778 -0.2794)
							(mid -0.249642 -0.249642)
							(end -0.2794 -0.1778)
						)
						(arc
							(start -0.2794 0.1778)
							(mid -0.249642 0.249642)
							(end -0.1778 0.2794)
						)
						(arc
							(start 0.1778 0.2794)
							(mid 0.249642 0.249642)
							(end 0.2794 0.1778)
						)
						(arc
							(start 0.2794 -0.1778)
							(mid 0.249642 -0.249642)
							(end 0.1778 -0.2794)
						)
					)
					(width 0)
					(fill yes)
				)
			)
		)
		(pad "2" smd custom
			(at 0 0.4445 180)
			(size 0.1397 0.1397)
			(layers "F.Cu" "F.Mask" "F.Paste")
			(net "SLOT2_VMONITOR_A1")
			(options
				(clearance outline)
				(anchor circle)
			)
			(primitives
				(gr_poly
					(pts
						(arc
							(start -0.1778 -0.2794)
							(mid -0.249642 -0.249642)
							(end -0.2794 -0.1778)
						)
						(arc
							(start -0.2794 0.1778)
							(mid -0.249642 0.249642)
							(end -0.1778 0.2794)
						)
						(arc
							(start 0.1778 0.2794)
							(mid 0.249642 0.249642)
							(end 0.2794 0.1778)
						)
						(arc
							(start 0.2794 -0.1778)
							(mid 0.249642 -0.249642)
							(end 0.1778 -0.2794)
						)
					)
					(width 0)
					(fill yes)
				)
			)
		)
	)
	(footprint ""
		(layer "F.Cu")
		(at 23.0124 -16.1798 -90)
		(property "Reference" "R85"
			(at 0 0 270)
			(layer "F.SilkS")
			(hide yes)
			(effects
				(font
					(size 1.27 1.27)
				)
			)
		)
		(property "Value" "10KR2F-2-GP"
			(at 0.064008 -3.993896 270)
			(unlocked yes)
			(layer "F.Fab")
			(hide yes)
			(effects
				(font
					(size 1.016 1.016)
					(thickness 0.1524)
				)
			)
		)
		(property "Device Type" "R402H16"
			(at 0.064008 -5.517896 270)
			(unlocked yes)
			(layer "F.Fab")
			(hide yes)
			(effects
				(font
					(size 1.016 1.016)
					(thickness 0.1524)
				)
			)
		)
		(duplicate_pad_numbers_are_jumpers no)
		(fp_line
			(start -0.508 -0.9398)
			(end -0.508 0.9398)
			(stroke
				(width 0.1524)
				(type default)
			)
			(layer "F.SilkS")
		)
		(fp_line
			(start 0.508 -0.9398)
			(end -0.508 -0.9398)
			(stroke
				(width 0.1524)
				(type default)
			)
			(layer "F.SilkS")
		)
		(fp_rect
			(start -0.508 0.9398)
			(end 0.508 -0.9398)
			(stroke
				(width 0)
				(type default)
			)
			(fill no)
			(layer "F.CrtYd")
		)
		(fp_rect
			(start -0.508 0.9398)
			(end 0.508 -0.9398)
			(stroke
				(width 0)
				(type default)
			)
			(fill no)
			(layer "F.Fab")
		)
		(pad "1" smd custom
			(at 0 -0.4445 270)
			(size 0.1397 0.1397)
			(layers "F.Cu" "F.Mask" "F.Paste")
			(net "P3V3_STBY")
			(options
				(clearance outline)
				(anchor circle)
			)
			(primitives
				(gr_poly
					(pts
						(arc
							(start -0.1778 -0.2794)
							(mid -0.249642 -0.249642)
							(end -0.2794 -0.1778)
						)
						(arc
							(start -0.2794 0.1778)
							(mid -0.249642 0.249642)
							(end -0.1778 0.2794)
						)
						(arc
							(start 0.1778 0.2794)
							(mid 0.249642 0.249642)
							(end 0.2794 0.1778)
						)
						(arc
							(start 0.2794 -0.1778)
							(mid 0.249642 -0.249642)
							(end 0.1778 -0.2794)
						)
					)
					(width 0)
					(fill yes)
				)
			)
		)
		(pad "2" smd custom
			(at 0 0.4445 270)
			(size 0.1397 0.1397)
			(layers "F.Cu" "F.Mask" "F.Paste")
			(net "SLOT2_VMONITOR_A0")
			(options
				(clearance outline)
				(anchor circle)
			)
			(primitives
				(gr_poly
					(pts
						(arc
							(start -0.1778 -0.2794)
							(mid -0.249642 -0.249642)
							(end -0.2794 -0.1778)
						)
						(arc
							(start -0.2794 0.1778)
							(mid -0.249642 0.249642)
							(end -0.1778 0.2794)
						)
						(arc
							(start 0.1778 0.2794)
							(mid 0.249642 0.249642)
							(end 0.2794 0.1778)
						)
						(arc
							(start 0.2794 -0.1778)
							(mid 0.249642 -0.249642)
							(end 0.1778 -0.2794)
						)
					)
					(width 0)
					(fill yes)
				)
			)
		)
	)
	(footprint ""
		(layer "F.Cu")
		(at 130.1496 0.4826 180)
		(property "Reference" "R95"
			(at 0 0 180)
			(layer "F.SilkS")
			(hide yes)
			(effects
				(font
					(size 1.27 1.27)
				)
			)
		)
		(property "Value" "0R2F-1-GP"
			(at 0.064008 -3.993896 180)
			(unlocked yes)
			(layer "F.Fab")
			(hide yes)
			(effects
				(font
					(size 1.016 1.016)
					(thickness 0.1524)
				)
			)
		)
		(property "Device Type" "R402H16"
			(at 0.064008 -5.517896 180)
			(unlocked yes)
			(layer "F.Fab")
			(hide yes)
			(effects
				(font
					(size 1.016 1.016)
					(thickness 0.1524)
				)
			)
		)
		(duplicate_pad_numbers_are_jumpers no)
		(fp_line
			(start 0.508 -0.9398)
			(end -0.508 -0.9398)
			(stroke
				(width 0.1524)
				(type default)
			)
			(layer "F.SilkS")
		)
		(fp_line
			(start -0.508 -0.9398)
			(end -0.508 0.9398)
			(stroke
				(width 0.1524)
				(type default)
			)
			(layer "F.SilkS")
		)
		(fp_rect
			(start -0.508 0.9398)
			(end 0.508 -0.9398)
			(stroke
				(width 0)
				(type default)
			)
			(fill no)
			(layer "F.CrtYd")
		)
		(fp_rect
			(start -0.508 0.9398)
			(end 0.508 -0.9398)
			(stroke
				(width 0)
				(type default)
			)
			(fill no)
			(layer "F.Fab")
		)
		(pad "1" smd custom
			(at 0 -0.4445 180)
			(size 0.1397 0.1397)
			(layers "F.Cu" "F.Mask" "F.Paste")
			(net "SMDAT_PCH_DEVICE")
			(options
				(clearance outline)
				(anchor circle)
			)
			(primitives
				(gr_poly
					(pts
						(arc
							(start -0.1778 -0.2794)
							(mid -0.249642 -0.249642)
							(end -0.2794 -0.1778)
						)
						(arc
							(start -0.2794 0.1778)
							(mid -0.249642 0.249642)
							(end -0.1778 0.2794)
						)
						(arc
							(start 0.1778 0.2794)
							(mid 0.249642 0.249642)
							(end 0.2794 0.1778)
						)
						(arc
							(start 0.2794 -0.1778)
							(mid 0.249642 -0.249642)
							(end 0.1778 -0.2794)
						)
					)
					(width 0)
					(fill yes)
				)
			)
		)
		(pad "2" smd custom
			(at 0 0.4445 180)
			(size 0.1397 0.1397)
			(layers "F.Cu" "F.Mask" "F.Paste")
			(net "SMDAT_EXP_R_PCH")
			(options
				(clearance outline)
				(anchor circle)
			)
			(primitives
				(gr_poly
					(pts
						(arc
							(start -0.1778 -0.2794)
							(mid -0.249642 -0.249642)
							(end -0.2794 -0.1778)
						)
						(arc
							(start -0.2794 0.1778)
							(mid -0.249642 0.249642)
							(end -0.1778 0.2794)
						)
						(arc
							(start 0.1778 0.2794)
							(mid 0.249642 0.249642)
							(end 0.2794 0.1778)
						)
						(arc
							(start 0.2794 -0.1778)
							(mid 0.249642 -0.249642)
							(end 0.1778 -0.2794)
						)
					)
					(width 0)
					(fill yes)
				)
			)
		)
	)
)
